# T6G (Grand Teton) — schematic netlist excerpt (pin names and nets, part order shuffled) for the footprints in the layout excerpt that follows; sources: Cadence DE-HDL packaged netlist, KiCad conversion of 04192023_DAF0TMB3IC0_F0TG_MB_C_brd_V02_OCP.brd

PC2201  Q_CAP  0.068UF 16V 10% X7R  pkg 0402  page 147 : A = P3V3_E1S_DVDT_0 ; B = GND
R3536  Q_RES  2.2K 5% CHIP  pkg 0402LF  page 250 : A = P3V3_AUX ; B = SMB_SENSOR_E1S_3V3AUX_SDA
C953  Q_CAP_DIFFBUS  DIFF BUS_0.22UF 6.3V 20% X6S  pkg C0201  page 63 : \1\ = P5E_CPU0_P1_TX_C_DP<6> ; \2\ = P5E_CPU0_P1_TX_DP<6>

(kicad_pcb
	(version 20260206)
	(generator "pcbnew")
	(generator_version "10.0")
	(general
		(thickness 1.6)
		(legacy_teardrops no)
	)
	(paper "A4")
	(title_block
		(title "04192023_DAF0TMB3IC0_F0TG_MB_C_brd_V02_OCP.brd")
		(comment 1 "Grand Teton / footprints 1366-1368 of 8354")
	)
	(layers
		(0 "F.Cu" signal "TOP")
		(4 "In1.Cu" signal "GND")
		(6 "In2.Cu" signal "IN1")
		(8 "In3.Cu" signal "GND1")
		(10 "In4.Cu" signal "IN2")
		(12 "In5.Cu" signal "GND2")
		(14 "In6.Cu" signal "IN3")
		(16 "In7.Cu" signal "GND3")
		(18 "In8.Cu" signal "VCC")
		(20 "In9.Cu" signal "VCC1")
		(22 "In10.Cu" signal "GND4")
		(24 "In11.Cu" signal "IN4")
		(26 "In12.Cu" signal "GND5")
		(28 "In13.Cu" signal "IN5")
		(30 "In14.Cu" signal "GND6")
		(32 "In15.Cu" signal "IN6")
		(34 "In16.Cu" signal "GND7")
		(2 "B.Cu" signal "BOTTOM")
		(9 "F.Adhes" user "F.Adhesive")
		(11 "B.Adhes" user "B.Adhesive")
		(13 "F.Paste" user "Package Geometry/Pastemask Top")
		(15 "B.Paste" user "Package Geometry/Pastemask Bottom")
		(5 "F.SilkS" user "Ref Des/Silkscreen Top")
		(7 "B.SilkS" user "Ref Des/Silkscreen Bottom")
		(1 "F.Mask" user "Board Geometry/Soldermask Top")
		(3 "B.Mask" user "Board Geometry/Soldermask Bottom")
		(17 "Dwgs.User" user "User.Drawings")
		(19 "Cmts.User" user "User.Comments")
		(21 "Eco1.User" user "User.Eco1")
		(23 "Eco2.User" user "User.Eco2")
		(25 "Edge.Cuts" user "Board Geometry/Outline")
		(27 "Margin" user)
		(31 "F.CrtYd" user "Package Geometry/Place Bound Top")
		(29 "B.CrtYd" user "Package Geometry/Place Bound Bottom")
		(35 "F.Fab" user "Ref Des/Assembly Top")
		(33 "B.Fab" user "Ref Des/Assembly Bottom")
	)
	(footprint ""
		(layer "F.Cu")
		(at 200.600564 -71.582788)
		(property "Reference" "PC2201"
			(at 0 0 0)
			(layer "F.SilkS")
			(hide yes)
			(effects
				(font
					(size 1.27 1.27)
				)
			)
		)
		(property "Value" ""
			(at 0 0 0)
			(layer "F.Fab")
			(effects
				(font
					(size 1.27 1.27)
				)
			)
		)
		(duplicate_pad_numbers_are_jumpers no)
		(fp_line
			(start -0.7874 -0.4064)
			(end 0.7874 -0.4064)
			(stroke
				(width 0.1524)
				(type default)
			)
			(layer "F.SilkS")
		)
		(fp_line
			(start -0.7874 0.4064)
			(end -0.7874 -0.4064)
			(stroke
				(width 0.1524)
				(type default)
			)
			(layer "F.SilkS")
		)
		(fp_line
			(start 0.7874 -0.4064)
			(end 0.7874 0.4064)
			(stroke
				(width 0.1524)
				(type default)
			)
			(layer "F.SilkS")
		)
		(fp_line
			(start 0.7874 0.4064)
			(end -0.7874 0.4064)
			(stroke
				(width 0.1524)
				(type default)
			)
			(layer "F.SilkS")
		)
		(fp_line
			(start -0.67945 -0.305054)
			(end -0.12065 -0.305054)
			(stroke
				(width 0.1)
				(type default)
			)
			(layer "F.Fab")
		)
		(fp_line
			(start -0.67945 0.3048)
			(end -0.67945 -0.305054)
			(stroke
				(width 0.1)
				(type default)
			)
			(layer "F.Fab")
		)
		(fp_line
			(start -0.12065 -0.305054)
			(end -0.12065 -0.2794)
			(stroke
				(width 0.1)
				(type default)
			)
			(layer "F.Fab")
		)
		(fp_line
			(start -0.12065 -0.2794)
			(end 0.12065 -0.2794)
			(stroke
				(width 0.1)
				(type default)
			)
			(layer "F.Fab")
		)
		(fp_line
			(start -0.12065 0.2794)
			(end -0.12065 0.3048)
			(stroke
				(width 0.1)
				(type default)
			)
			(layer "F.Fab")
		)
		(fp_line
			(start -0.12065 0.3048)
			(end -0.67945 0.3048)
			(stroke
				(width 0.1)
				(type default)
			)
			(layer "F.Fab")
		)
		(fp_line
			(start 0.120396 0.2794)
			(end -0.12065 0.2794)
			(stroke
				(width 0.1)
				(type default)
			)
			(layer "F.Fab")
		)
		(fp_line
			(start 0.120396 0.3048)
			(end 0.120396 0.2794)
			(stroke
				(width 0.1)
				(type default)
			)
			(layer "F.Fab")
		)
		(fp_line
			(start 0.12065 -0.3048)
			(end 0.67945 -0.3048)
			(stroke
				(width 0.1)
				(type default)
			)
			(layer "F.Fab")
		)
		(fp_line
			(start 0.12065 -0.2794)
			(end 0.12065 -0.3048)
			(stroke
				(width 0.1)
				(type default)
			)
			(layer "F.Fab")
		)
		(fp_line
			(start 0.67945 -0.3048)
			(end 0.67945 0.3048)
			(stroke
				(width 0.1)
				(type default)
			)
			(layer "F.Fab")
		)
		(fp_line
			(start 0.67945 0.3048)
			(end 0.120396 0.3048)
			(stroke
				(width 0.1)
				(type default)
			)
			(layer "F.Fab")
		)
		(pad "1" smd circle
			(at -0.40005 0)
			(size 0 0)
			(layers "F.Cu" "F.Mask" "F.Paste")
			(net "P3V3_E1S_DVDT_0")
		)
		(pad "2" smd circle
			(at 0.40005 0)
			(size 0 0)
			(layers "F.Cu" "F.Mask" "F.Paste")
			(net "GND")
		)
	)
	(footprint ""
		(layer "F.Cu")
		(at 277.352252 -113.31067)
		(property "Reference" "R3536"
			(at 0 0 0)
			(layer "F.SilkS")
			(hide yes)
			(effects
				(font
					(size 1.27 1.27)
				)
			)
		)
		(property "Value" ""
			(at 0 0 0)
			(layer "F.Fab")
			(effects
				(font
					(size 1.27 1.27)
				)
			)
		)
		(duplicate_pad_numbers_are_jumpers no)
		(fp_line
			(start -0.7874 -0.4064)
			(end 0.7874 -0.4064)
			(stroke
				(width 0.1524)
				(type default)
			)
			(layer "F.SilkS")
		)
		(fp_line
			(start -0.7874 0.4064)
			(end -0.7874 -0.4064)
			(stroke
				(width 0.1524)
				(type default)
			)
			(layer "F.SilkS")
		)
		(fp_line
			(start 0.7874 -0.4064)
			(end 0.7874 0.4064)
			(stroke
				(width 0.1524)
				(type default)
			)
			(layer "F.SilkS")
		)
		(fp_line
			(start 0.7874 0.4064)
			(end -0.7874 0.4064)
			(stroke
				(width 0.1524)
				(type default)
			)
			(layer "F.SilkS")
		)
		(fp_line
			(start -0.67945 -0.305054)
			(end -0.12065 -0.305054)
			(stroke
				(width 0.1)
				(type default)
			)
			(layer "F.Fab")
		)
		(fp_line
			(start -0.67945 0.3048)
			(end -0.67945 -0.305054)
			(stroke
				(width 0.1)
				(type default)
			)
			(layer "F.Fab")
		)
		(fp_line
			(start -0.12065 -0.305054)
			(end -0.12065 -0.2794)
			(stroke
				(width 0.1)
				(type default)
			)
			(layer "F.Fab")
		)
		(fp_line
			(start -0.12065 -0.2794)
			(end 0.12065 -0.2794)
			(stroke
				(width 0.1)
				(type default)
			)
			(layer "F.Fab")
		)
		(fp_line
			(start -0.12065 0.2794)
			(end -0.12065 0.3048)
			(stroke
				(width 0.1)
				(type default)
			)
			(layer "F.Fab")
		)
		(fp_line
			(start -0.12065 0.3048)
			(end -0.67945 0.3048)
			(stroke
				(width 0.1)
				(type default)
			)
			(layer "F.Fab")
		)
		(fp_line
			(start 0.120396 0.2794)
			(end -0.12065 0.2794)
			(stroke
				(width 0.1)
				(type default)
			)
			(layer "F.Fab")
		)
		(fp_line
			(start 0.120396 0.3048)
			(end 0.120396 0.2794)
			(stroke
				(width 0.1)
				(type default)
			)
			(layer "F.Fab")
		)
		(fp_line
			(start 0.12065 -0.3048)
			(end 0.67945 -0.3048)
			(stroke
				(width 0.1)
				(type default)
			)
			(layer "F.Fab")
		)
		(fp_line
			(start 0.12065 -0.2794)
			(end 0.12065 -0.3048)
			(stroke
				(width 0.1)
				(type default)
			)
			(layer "F.Fab")
		)
		(fp_line
			(start 0.67945 -0.3048)
			(end 0.67945 0.3048)
			(stroke
				(width 0.1)
				(type default)
			)
			(layer "F.Fab")
		)
		(fp_line
			(start 0.67945 0.3048)
			(end 0.120396 0.3048)
			(stroke
				(width 0.1)
				(type default)
			)
			(layer "F.Fab")
		)
		(pad "1" smd circle
			(at -0.40005 0)
			(size 0 0)
			(layers "F.Cu" "F.Mask" "F.Paste")
			(net "P3V3_AUX")
		)
		(pad "2" smd circle
			(at 0.40005 0)
			(size 0 0)
			(layers "F.Cu" "F.Mask" "F.Paste")
			(net "SMB_SENSOR_E1S_3V3AUX_SDA")
		)
	)
	(footprint ""
		(layer "F.Cu")
		(at 340.026244 -378.95403 -90)
		(property "Reference" "C953"
			(at 0 0 270)
			(layer "F.SilkS")
			(hide yes)
			(effects
				(font
					(size 1.27 1.27)
				)
			)
		)
		(property "Value" ""
			(at 0 0 270)
			(layer "F.Fab")
			(effects
				(font
					(size 1.27 1.27)
				)
			)
		)
		(duplicate_pad_numbers_are_jumpers no)
		(fp_line
			(start -0.299974 0.150114)
			(end -0.299974 -0.150114)
			(stroke
				(width 0.1)
				(type default)
			)
			(layer "F.Fab")
		)
		(fp_line
			(start 0.299974 0.150114)
			(end -0.299974 0.150114)
			(stroke
				(width 0.1)
				(type default)
			)
			(layer "F.Fab")
		)
		(fp_line
			(start -0.299974 -0.150114)
			(end 0.299974 -0.150114)
			(stroke
				(width 0.1)
				(type default)
			)
			(layer "F.Fab")
		)
		(fp_line
			(start 0.299974 -0.150114)
			(end 0.299974 0.150114)
			(stroke
				(width 0.1)
				(type default)
			)
			(layer "F.Fab")
		)
		(pad "1" smd rect
			(at -0.2667 0 270)
			(size 0.3048 0.381)
			(layers "F.Cu" "F.Mask" "F.Paste")
			(net "P5E_CPU0_P1_TX_C_DP<6>")
		)
		(pad "2" smd rect
			(at 0.2667 0 270)
			(size 0.3048 0.381)
			(layers "F.Cu" "F.Mask" "F.Paste")
			(net "P5E_CPU0_P1_TX_DP<6>")
		)
	)
)
